# S9S_MB_2U (Grand Teton) — schematic netlist excerpt (pin names and nets, part order shuffled) for the footprints in the layout excerpt that follows; sources: Cadence DE-HDL packaged netlist, KiCad conversion of 03242023_DA0F0TMBIJ0_F0T_Motherboard_J_brd_V01_OCP.brd

J9  SCONN288_ADR50017P130CC  SCONN288_ADR50017-P130CC IO  pkg DDR288S_1-1VXB  page 90
  VIN_BULK0  = P12V_S3_AUX_CPU0_NVDIMM
  RFU0  = TP_CHE_CPU0_DIMM1_FRU_0
  VIN_MGMT  = P3V3_AUX
  HSCL  = I3C_SPD_DDREFGH_CPU0_LVC1_SCL_R
  HSDA  = I3C_SPD_DDREFGH_CPU0_LVC1_SDA
  VSS0  = GND
  DQ0_A  = M_E_CPU0_SA_DQ<0>
  VSS1  = GND
  DQ1_A  = M_E_CPU0_SA_DQ<1>
  VSS2  = GND
  DQS0_A_T  = M_E_CPU0_SA_DQS_DP<0>
  DQS0_A_C  = M_E_CPU0_SA_DQS_DN<0>
  VSS3  = GND
  DQ4_A  = M_E_CPU0_SA_DQ<4>
  VSS4  = GND
  DQ5_A  = M_E_CPU0_SA_DQ<5>
  VSS5  = GND
  DQ8_A  = M_E_CPU0_SA_DQ<8>
  VSS6  = GND
  DQ9_A  = M_E_CPU0_SA_DQ<9>
  VSS7  = GND
  DQS1_A_T  = M_E_CPU0_SA_DQS_DP<1>
  DQS1_A_C  = M_E_CPU0_SA_DQS_DN<1>
  VSS8  = GND
  DQ12_A  = M_E_CPU0_SA_DQ<12>
  VSS9  = GND
  DQ13_A  = M_E_CPU0_SA_DQ<13>
  VSS10  = GND
  DQ16_A  = M_E_CPU0_SA_DQ<16>
  VSS11  = GND
  DQ17_A  = M_E_CPU0_SA_DQ<17>
  VSS12  = GND
  DQS2_A_T  = M_E_CPU0_SA_DQS_DP<2>
  DQS2_A_C  = M_E_CPU0_SA_DQS_DN<2>
  VSS13  = GND
  DQ20_A  = M_E_CPU0_SA_DQ<20>
  VSS14  = GND
  DQ21_A  = M_E_CPU0_SA_DQ<21>
  VSS15  = GND
  DQ24_A  = M_E_CPU0_SA_DQ<24>
  VSS16  = GND
  DQ25_A  = M_E_CPU0_SA_DQ<25>
  VSS17  = GND
  DQS3_A_T  = M_E_CPU0_SA_DQS_DP<3>
  DQS3_A_C  = M_E_CPU0_SA_DQS_DN<3>
  VSS18  = GND
  DQ28_A  = M_E_CPU0_SA_DQ<28>
  VSS19  = GND
  DQ29_A  = M_E_CPU0_SA_DQ<29>
  VSS20  = GND
  CB0_A  = M_E_CPU0_SA_CB<0>
  VSS21  = GND
  CB1_A  = M_E_CPU0_SA_CB<1>
  VSS22  = GND
  DQS4_A_T  = M_E_CPU0_SA_DQS_DP<4>
  DQS4_A_C  = M_E_CPU0_SA_DQS_DN<4>
  VSS23  = GND
  CB4_A  = M_E_CPU0_SA_CB<4>
  VSS24  = GND
  CB5_A  = M_E_CPU0_SA_CB<5>
  VSS25  = GND
  ALERT_N  = M_E_CPU0_ALERT_N
  VSS26  = GND
  CS0_A_N  = M_E_CPU0_SA_CS_N<0>
  VSS27  = GND
  CA0_A  = M_E_CPU0_SA_CA<0>
  VSS28  = GND
  CA2_A  = M_E_CPU0_SA_CA<2>
  VSS29  = GND
  CA4_A  = M_E_CPU0_SA_CA<4>
  VSS30  = GND
  CA6_A  = M_E_CPU0_SA_CA<6>
  VSS31  = GND
  PAR_A  = M_E_CPU0_SA_PAR
  VSS32  = GND
  CA0_B  = M_E_CPU0_SB_CA<0>
  VSS33  = GND
  CA2_B  = M_E_CPU0_SB_CA<2>
  VSS34  = GND
  CA4_B  = M_E_CPU0_SB_CA<4>
  VSS35  = GND
  CA6_B  = M_E_CPU0_SB_CA<6>
  VSS36  = GND
  CS0_B_N  = M_E_CPU0_SB_CS_N<0>
  VSS37  = GND
  \lbd||rsp_a_n\  = M_E_CPU0_SA_RSP<0>
  \lbs||rsp_b_n\  = M_E_CPU0_SB_RSP<0>
  VSS38  = GND
  CB4_B  = M_E_CPU0_SB_CB<4>
  VSS39  = GND
  CB5_B  = M_E_CPU0_SB_CB<5>
  VSS40  = GND
  \dqs9_b_t||tdqs9_b_t||dbi4_b_n\  = M_E_CPU0_SB_DQS_DP<9>
  \dqs9_b_c||tdqs9_b_c\  = M_E_CPU0_SB_DQS_DN<9>
  VSS41  = GND
  CB0_B  = M_E_CPU0_SB_CB<0>
  VSS42  = GND
  CB1_B  = M_E_CPU0_SB_CB<1>
  VSS43  = GND
  DQ0_B  = M_E_CPU0_SB_DQ<0>
  VSS44  = GND
  DQ1_B  = M_E_CPU0_SB_DQ<1>
  VSS45  = GND
  DQS0_B_T  = M_E_CPU0_SB_DQS_DP<0>
  DQS0_B_C  = M_E_CPU0_SB_DQS_DN<0>
  VSS46  = GND
  DQ4_B  = M_E_CPU0_SB_DQ<4>
  VSS47  = GND
  DQ5_B  = M_E_CPU0_SB_DQ<5>
  VSS48  = GND
  DQ8_B  = M_E_CPU0_SB_DQ<8>
  VSS49  = GND
  DQ9_B  = M_E_CPU0_SB_DQ<9>
  VSS50  = GND
  DQS1_B_T  = M_E_CPU0_SB_DQS_DP<1>
  DQS1_B_C  = M_E_CPU0_SB_DQS_DN<1>
  VSS51  = GND
  DQ12_B  = M_E_CPU0_SB_DQ<12>
  VSS52  = GND
  DQ13_B  = M_E_CPU0_SB_DQ<13>
  VSS53  = GND
  DQ16_B  = M_E_CPU0_SB_DQ<16>
  VSS54  = GND
  DQ17_B  = M_E_CPU0_SB_DQ<17>
  VSS55  = GND
  DQS2_B_T  = M_E_CPU0_SB_DQS_DP<2>
  DQS2_B_C  = M_E_CPU0_SB_DQS_DN<2>
  VSS56  = GND
  DQ20_B  = M_E_CPU0_SB_DQ<20>
  VSS57  = GND
  DQ21_B  = M_E_CPU0_SB_DQ<21>
  VSS58  = GND
  DQ24_B  = M_E_CPU0_SB_DQ<24>
  VSS59  = GND
  DQ25_B  = M_E_CPU0_SB_DQ<25>
  VSS60  = GND
  DQS3_B_T  = M_E_CPU0_SB_DQS_DP<3>
  DQS3_B_C  = M_E_CPU0_SB_DQS_DN<3>
  VSS61  = GND
  DQ28_B  = M_E_CPU0_SB_DQ<28>
  VSS62  = GND
  DQ29_B  = M_E_CPU0_SB_DQ<29>
  VSS63  = GND
  RFU1  = TP_CHE_CPU0_DIMM1_FRU_1
  VIN_BULK1  = P12V_S3_AUX_CPU0_NVDIMM
  VIN_BULK2  = P12V_S3_AUX_CPU0_NVDIMM
  \pwr_good||fail_n\  = PWRGD_CHE_CPU0_DIMM1
  HSA  = PD_CHE_CPU0_DIMM1_SAA
  RFU2  = TP_CHE_CPU0_DIMM1_FRU_2
  RFU3  = TP_CHE_CPU0_DIMM1_FRU_3
  VSS64  = GND
  DQ2_A  = M_E_CPU0_SA_DQ<2>
  VSS65  = GND
  DQ3_A  = M_E_CPU0_SA_DQ<3>
  VSS66  = GND
  \dqs5_a_c||tdqs5_a_c||dqs5_a_t||tdqs5_a_t\  = M_E_CPU0_SA_DQS_DN<5>
  \dqs5_a_t||tdqs5_a_t\  = M_E_CPU0_SA_DQS_DP<5>
  VSS67  = GND
  DQ6_A  = M_E_CPU0_SA_DQ<6>
  VSS68  = GND
  DQ7_A  = M_E_CPU0_SA_DQ<7>
  VSS69  = GND
  DQ10_A  = M_E_CPU0_SA_DQ<10>
  VSS70  = GND
  DQ11_A  = M_E_CPU0_SA_DQ<11>
  VSS71  = GND
  \dqs6_a_c||tdqs6_a_c||dqs6_a_t||tdqs6_a_t\  = M_E_CPU0_SA_DQS_DN<6>
  \dqs6_a_t||tdqs6_a_t\  = M_E_CPU0_SA_DQS_DP<6>
  VSS72  = GND
  DQ14_A  = M_E_CPU0_SA_DQ<14>
  VSS73  = GND
  DQ15_A  = M_E_CPU0_SA_DQ<15>
  VSS74  = GND
  DQ18_A  = M_E_CPU0_SA_DQ<18>
  VSS75  = GND
  DQ19_A  = M_E_CPU0_SA_DQ<19>
  VSS76  = GND
  \dqs7_a_c||tdqs7_a_c\  = M_E_CPU0_SA_DQS_DN<7>
  \dqs7_a_t||tdqs7_a_t\  = M_E_CPU0_SA_DQS_DP<7>
  VSS77  = GND
  DQ22_A  = M_E_CPU0_SA_DQ<22>
  VSS78  = GND
  DQ23_A  = M_E_CPU0_SA_DQ<23>
  VSS79  = GND
  DQ26_A  = M_E_CPU0_SA_DQ<26>
  VSS80  = GND
  DQ27_A  = M_E_CPU0_SA_DQ<27>
  VSS81  = GND
  \dqs8_a_c||tdqs8_a_c\  = M_E_CPU0_SA_DQS_DN<8>
  \dqs8_a_t||tdqs8_a_t\  = M_E_CPU0_SA_DQS_DP<8>
  VSS82  = GND
  DQ30_A  = M_E_CPU0_SA_DQ<30>
  VSS83  = GND
  DQ31_A  = M_E_CPU0_SA_DQ<31>
  VSS84  = GND
  CB2_A  = M_E_CPU0_SA_CB<2>
  VSS85  = GND
  CB3_A  = M_E_CPU0_SA_CB<3>
  VSS86  = GND
  \dqs9_a_c||tdqs9_a_c\  = M_E_CPU0_SA_DQS_DN<9>
  \dqs9_a_t||tdqs9_a_t\  = M_E_CPU0_SA_DQS_DP<9>
  VSS87  = GND
  CB6_A  = M_E_CPU0_SA_CB<6>
  VSS88  = GND
  CB7_A  = M_E_CPU0_SA_CB<7>
  VSS89  = GND
  RESET_N  = RST_M_EF_CPU0_FPGA_N
  VSS90  = GND
  CS1_A_N  = M_E_CPU0_SA_CS_N<1>
  VSS91  = GND
  CA1_A  = M_E_CPU0_SA_CA<1>
  VSS92  = GND
  CA3_A  = M_E_CPU0_SA_CA<3>
  VSS93  = GND
  CA5_A  = M_E_CPU0_SA_CA<5>
  VSS94  = GND
  CK_T  = M_E_CPU0_CLK_DP<0>
  CK_C  = M_E_CPU0_CLK_DN<0>
  VSS95  = GND
  RFU4  = TP_CHE_CPU0_DIMM1_FRU_4
  CA1_B  = M_E_CPU0_SB_CA<1>
  VSS96  = GND
  CA3_B  = M_E_CPU0_SB_CA<3>
  VSS97  = GND
  CA5_B  = M_E_CPU0_SB_CA<5>
  VSS98  = GND
  PAR_B  = M_E_CPU0_SB_PAR
  VSS99  = GND
  CS1_B_N  = M_E_CPU0_SB_CS_N<1>
  VSS100  = GND
  RFU5  = TP_CHE_CPU0_DIMM1_FRU_5
  RFU6  = TP_CHE_CPU0_DIMM1_FRU_6
  VSS101  = GND
  CB6_B  = M_E_CPU0_SB_CB<6>
  VSS102  = GND
  CB7_B  = M_E_CPU0_SB_CB<7>
  VSS103  = GND
  DQS4_B_C  = M_E_CPU0_SB_DQS_DN<4>
  DQS4_B_T  = M_E_CPU0_SB_DQS_DP<4>
  VSS104  = GND
  CB2_B  = M_E_CPU0_SB_CB<2>
  VSS105  = GND
  CB3_B  = M_E_CPU0_SB_CB<3>
  VSS106  = GND
  DQ2_B  = M_E_CPU0_SB_DQ<2>
  VSS107  = GND
  DQ3_B  = M_E_CPU0_SB_DQ<3>
  VSS108  = GND
  \dqs5_b_c||tdqs5_b_c\  = M_E_CPU0_SB_DQS_DN<5>
  \dqs5_b_t||tdqs5_b_t\  = M_E_CPU0_SB_DQS_DP<5>
  VSS109  = GND
  DQ6_B  = M_E_CPU0_SB_DQ<6>
  VSS110  = GND
  DQ7_B  = M_E_CPU0_SB_DQ<7>
  VSS111  = GND
  DQ10_B  = M_E_CPU0_SB_DQ<10>
  VSS112  = GND
  DQ11_B  = M_E_CPU0_SB_DQ<11>
  VSS113  = GND
  \dqs6_b_c||tdqs6_b_c\  = M_E_CPU0_SB_DQS_DN<6>
  \dqs6_b_t||tdqs6_b_t\  = M_E_CPU0_SB_DQS_DP<6>
  VSS114  = GND
  DQ14_B  = M_E_CPU0_SB_DQ<14>
  VSS115  = GND
  DQ15_B  = M_E_CPU0_SB_DQ<15>
  VSS116  = GND
  DQ18_B  = M_E_CPU0_SB_DQ<18>
  VSS117  = GND
  DQ19_B  = M_E_CPU0_SB_DQ<19>
  VSS118  = GND
  \dqs7_b_c||tdqs7_b_c\  = M_E_CPU0_SB_DQS_DN<7>
  \dqs7_b_t||tdqs7_b_t\  = M_E_CPU0_SB_DQS_DP<7>
  VSS119  = GND
  DQ22_B  = M_E_CPU0_SB_DQ<22>
  VSS120  = GND
  DQ23_B  = M_E_CPU0_SB_DQ<23>
  VSS121  = GND
  DQ26_B  = M_E_CPU0_SB_DQ<26>
  VSS122  = GND
  DQ27_B  = M_E_CPU0_SB_DQ<27>
  VSS123  = GND
  \dqs8_b_c||tdqs8_b_c\  = M_E_CPU0_SB_DQS_DN<8>
  \dqs8_b_t||tdqs8_b_t\  = M_E_CPU0_SB_DQS_DP<8>
  VSS124  = GND
  DQ30_B  = M_E_CPU0_SB_DQ<30>
  VSS125  = GND
  DQ31_B  = M_E_CPU0_SB_DQ<31>
  VSS126  = GND
  G1  = GND
  G2  = GND
  G3  = GND

(kicad_pcb
	(version 20260206)
	(generator "pcbnew")
	(generator_version "10.0")
	(general
		(thickness 1.6)
		(legacy_teardrops no)
	)
	(paper "A4")
	(title_block
		(title "03242023_DA0F0TMBIJ0_F0T_Motherboard_J_brd_V01_OCP.brd")
		(comment 1 "Grand Teton / footprint 461 of 6105 (J9), pads 229-274 of 291")
	)
	(layers
		(0 "F.Cu" signal "TOP")
		(4 "In1.Cu" signal "GND")
		(6 "In2.Cu" signal "IN1")
		(8 "In3.Cu" signal "GND1")
		(10 "In4.Cu" signal "IN2")
		(12 "In5.Cu" signal "GND2")
		(14 "In6.Cu" signal "IN3")
		(16 "In7.Cu" signal "GND3")
		(18 "In8.Cu" signal "VCC")
		(20 "In9.Cu" signal "VCC1")
		(22 "In10.Cu" signal "GND4")
		(24 "In11.Cu" signal "IN4")
		(26 "In12.Cu" signal "GND5")
		(28 "In13.Cu" signal "IN5")
		(30 "In14.Cu" signal "GND6")
		(32 "In15.Cu" signal "IN6")
		(34 "In16.Cu" signal "GND7")
		(2 "B.Cu" signal "BOTTOM")
		(9 "F.Adhes" user "F.Adhesive")
		(11 "B.Adhes" user "B.Adhesive")
		(13 "F.Paste" user "Package Geometry/Pastemask Top")
		(15 "B.Paste" user "Package Geometry/Pastemask Bottom")
		(5 "F.SilkS" user "Ref Des/Silkscreen Top")
		(7 "B.SilkS" user "Ref Des/Silkscreen Bottom")
		(1 "F.Mask" user "Board Geometry/Soldermask Top")
		(3 "B.Mask" user "Board Geometry/Soldermask Bottom")
		(17 "Dwgs.User" user "User.Drawings")
		(19 "Cmts.User" user "User.Comments")
		(21 "Eco1.User" user "User.Eco1")
		(23 "Eco2.User" user "User.Eco2")
		(25 "Edge.Cuts" user "Board Geometry/Outline")
		(27 "Margin" user)
		(31 "F.CrtYd" user "Package Geometry/Place Bound Top")
		(29 "B.CrtYd" user "Package Geometry/Place Bound Bottom")
		(35 "F.Fab" user "Ref Des/Assembly Top")
		(33 "B.Fab" user "Ref Des/Assembly Bottom")
	)
	(footprint ""
		(layer "F.Cu")
		(at 416.347148 -258.091686)
		(property "Reference" "J9"
			(at -3.683 -81.702148 0)
			(unlocked yes)
			(layer "F.SilkS")
			(effects
				(font
					(size 0.7874 0.5842)
					(thickness 0.1524)
				)
				(justify left)
			)
		)
		(property "Value" ""
			(at 0 0 0)
			(layer "F.Fab")
			(effects
				(font
					(size 1.27 1.27)
				)
			)
		)
		(duplicate_pad_numbers_are_jumpers no)
		(pad "229" smd rect
			(at 2.050034 13.17498 270)
			(size 0.519938 1.4986)
			(layers "F.Cu" "F.Mask" "F.Paste")
			(net "M_E_CPU0_SB_CS_N<1>")
		)
		(pad "230" smd rect
			(at 2.050034 14.025118 270)
			(size 0.519938 1.4986)
			(layers "F.Cu" "F.Mask" "F.Paste")
			(net "GND")
		)
		(pad "231" smd rect
			(at 2.050034 14.875002 270)
			(size 0.519938 1.4986)
			(layers "F.Cu" "F.Mask" "F.Paste")
			(net "TP_CHE_CPU0_DIMM1_FRU_5")
		)
		(pad "232" smd rect
			(at 2.050034 15.724886 270)
			(size 0.519938 1.4986)
			(layers "F.Cu" "F.Mask" "F.Paste")
			(net "TP_CHE_CPU0_DIMM1_FRU_6")
		)
		(pad "233" smd rect
			(at 2.050034 16.575024 270)
			(size 0.519938 1.4986)
			(layers "F.Cu" "F.Mask" "F.Paste")
			(net "GND")
		)
		(pad "234" smd rect
			(at 2.050034 17.424908 270)
			(size 0.519938 1.4986)
			(layers "F.Cu" "F.Mask" "F.Paste")
			(net "M_E_CPU0_SB_CB<6>")
		)
		(pad "235" smd rect
			(at 2.050034 18.275046 270)
			(size 0.519938 1.4986)
			(layers "F.Cu" "F.Mask" "F.Paste")
			(net "GND")
		)
		(pad "236" smd rect
			(at 2.050034 19.12493 270)
			(size 0.519938 1.4986)
			(layers "F.Cu" "F.Mask" "F.Paste")
			(net "M_E_CPU0_SB_CB<7>")
		)
		(pad "237" smd rect
			(at 2.050034 19.975068 270)
			(size 0.519938 1.4986)
			(layers "F.Cu" "F.Mask" "F.Paste")
			(net "GND")
		)
		(pad "238" smd rect
			(at 2.050034 20.824952 270)
			(size 0.519938 1.4986)
			(layers "F.Cu" "F.Mask" "F.Paste")
			(net "M_E_CPU0_SB_DQS_DN<4>")
		)
		(pad "239" smd rect
			(at 2.050034 21.67509 270)
			(size 0.519938 1.4986)
			(layers "F.Cu" "F.Mask" "F.Paste")
			(net "M_E_CPU0_SB_DQS_DP<4>")
		)
		(pad "240" smd rect
			(at 2.050034 22.524974 270)
			(size 0.519938 1.4986)
			(layers "F.Cu" "F.Mask" "F.Paste")
			(net "GND")
		)
		(pad "241" smd rect
			(at 2.050034 23.375112 270)
			(size 0.519938 1.4986)
			(layers "F.Cu" "F.Mask" "F.Paste")
			(net "M_E_CPU0_SB_CB<2>")
		)
		(pad "242" smd rect
			(at 2.050034 24.224996 270)
			(size 0.519938 1.4986)
			(layers "F.Cu" "F.Mask" "F.Paste")
			(net "GND")
		)
		(pad "243" smd rect
			(at 2.050034 25.07488 270)
			(size 0.519938 1.4986)
			(layers "F.Cu" "F.Mask" "F.Paste")
			(net "M_E_CPU0_SB_CB<3>")
		)
		(pad "244" smd rect
			(at 2.050034 25.925018 270)
			(size 0.519938 1.4986)
			(layers "F.Cu" "F.Mask" "F.Paste")
			(net "GND")
		)
		(pad "245" smd rect
			(at 2.050034 26.774902 270)
			(size 0.519938 1.4986)
			(layers "F.Cu" "F.Mask" "F.Paste")
			(net "M_E_CPU0_SB_DQ<2>")
		)
		(pad "246" smd rect
			(at 2.050034 27.62504 270)
			(size 0.519938 1.4986)
			(layers "F.Cu" "F.Mask" "F.Paste")
			(net "GND")
		)
		(pad "247" smd rect
			(at 2.050034 28.474924 270)
			(size 0.519938 1.4986)
			(layers "F.Cu" "F.Mask" "F.Paste")
			(net "M_E_CPU0_SB_DQ<3>")
		)
		(pad "248" smd rect
			(at 2.050034 29.325062 270)
			(size 0.519938 1.4986)
			(layers "F.Cu" "F.Mask" "F.Paste")
			(net "GND")
		)
		(pad "249" smd rect
			(at 2.050034 30.174946 270)
			(size 0.519938 1.4986)
			(layers "F.Cu" "F.Mask" "F.Paste")
			(net "M_E_CPU0_SB_DQS_DN<5>")
		)
		(pad "250" smd rect
			(at 2.050034 31.025084 270)
			(size 0.519938 1.4986)
			(layers "F.Cu" "F.Mask" "F.Paste")
			(net "M_E_CPU0_SB_DQS_DP<5>")
		)
		(pad "251" smd rect
			(at 2.050034 31.874968 270)
			(size 0.519938 1.4986)
			(layers "F.Cu" "F.Mask" "F.Paste")
			(net "GND")
		)
		(pad "252" smd rect
			(at 2.050034 32.725106 270)
			(size 0.519938 1.4986)
			(layers "F.Cu" "F.Mask" "F.Paste")
			(net "M_E_CPU0_SB_DQ<6>")
		)
		(pad "253" smd rect
			(at 2.050034 33.57499 270)
			(size 0.519938 1.4986)
			(layers "F.Cu" "F.Mask" "F.Paste")
			(net "GND")
		)
		(pad "254" smd rect
			(at 2.050034 34.425128 270)
			(size 0.519938 1.4986)
			(layers "F.Cu" "F.Mask" "F.Paste")
			(net "M_E_CPU0_SB_DQ<7>")
		)
		(pad "255" smd rect
			(at 2.050034 35.275012 270)
			(size 0.519938 1.4986)
			(layers "F.Cu" "F.Mask" "F.Paste")
			(net "GND")
		)
		(pad "256" smd rect
			(at 2.050034 36.124896 270)
			(size 0.519938 1.4986)
			(layers "F.Cu" "F.Mask" "F.Paste")
			(net "M_E_CPU0_SB_DQ<10>")
		)
		(pad "257" smd rect
			(at 2.050034 36.975034 270)
			(size 0.519938 1.4986)
			(layers "F.Cu" "F.Mask" "F.Paste")
			(net "GND")
		)
		(pad "258" smd rect
			(at 2.050034 37.824918 270)
			(size 0.519938 1.4986)
			(layers "F.Cu" "F.Mask" "F.Paste")
			(net "M_E_CPU0_SB_DQ<11>")
		)
		(pad "259" smd rect
			(at 2.050034 38.675056 270)
			(size 0.519938 1.4986)
			(layers "F.Cu" "F.Mask" "F.Paste")
			(net "GND")
		)
		(pad "260" smd rect
			(at 2.050034 39.52494 270)
			(size 0.519938 1.4986)
			(layers "F.Cu" "F.Mask" "F.Paste")
			(net "M_E_CPU0_SB_DQS_DN<6>")
		)
		(pad "261" smd rect
			(at 2.050034 40.375078 270)
			(size 0.519938 1.4986)
			(layers "F.Cu" "F.Mask" "F.Paste")
			(net "M_E_CPU0_SB_DQS_DP<6>")
		)
		(pad "262" smd rect
			(at 2.050034 41.224962 270)
			(size 0.519938 1.4986)
			(layers "F.Cu" "F.Mask" "F.Paste")
			(net "GND")
		)
		(pad "263" smd rect
			(at 2.050034 42.0751 270)
			(size 0.519938 1.4986)
			(layers "F.Cu" "F.Mask" "F.Paste")
			(net "M_E_CPU0_SB_DQ<14>")
		)
		(pad "264" smd rect
			(at 2.050034 42.924984 270)
			(size 0.519938 1.4986)
			(layers "F.Cu" "F.Mask" "F.Paste")
			(net "GND")
		)
		(pad "265" smd rect
			(at 2.050034 43.775122 270)
			(size 0.519938 1.4986)
			(layers "F.Cu" "F.Mask" "F.Paste")
			(net "M_E_CPU0_SB_DQ<15>")
		)
		(pad "266" smd rect
			(at 2.050034 44.625006 270)
			(size 0.519938 1.4986)
			(layers "F.Cu" "F.Mask" "F.Paste")
			(net "GND")
		)
		(pad "267" smd rect
			(at 2.050034 45.47489 270)
			(size 0.519938 1.4986)
			(layers "F.Cu" "F.Mask" "F.Paste")
			(net "M_E_CPU0_SB_DQ<18>")
		)
		(pad "268" smd rect
			(at 2.050034 46.325028 270)
			(size 0.519938 1.4986)
			(layers "F.Cu" "F.Mask" "F.Paste")
			(net "GND")
		)
		(pad "269" smd rect
			(at 2.050034 47.174912 270)
			(size 0.519938 1.4986)
			(layers "F.Cu" "F.Mask" "F.Paste")
			(net "M_E_CPU0_SB_DQ<19>")
		)
		(pad "270" smd rect
			(at 2.050034 48.02505 270)
			(size 0.519938 1.4986)
			(layers "F.Cu" "F.Mask" "F.Paste")
			(net "GND")
		)
		(pad "271" smd rect
			(at 2.050034 48.874934 270)
			(size 0.519938 1.4986)
			(layers "F.Cu" "F.Mask" "F.Paste")
			(net "M_E_CPU0_SB_DQS_DN<7>")
		)
		(pad "272" smd rect
			(at 2.050034 49.725072 270)
			(size 0.519938 1.4986)
			(layers "F.Cu" "F.Mask" "F.Paste")
			(net "M_E_CPU0_SB_DQS_DP<7>")
		)
		(pad "273" smd rect
			(at 2.050034 50.574956 270)
			(size 0.519938 1.4986)
			(layers "F.Cu" "F.Mask" "F.Paste")
			(net "GND")
		)
		(pad "274" smd rect
			(at 2.050034 51.425094 270)
			(size 0.519938 1.4986)
			(layers "F.Cu" "F.Mask" "F.Paste")
			(net "M_E_CPU0_SB_DQ<22>")
		)
	)
)
